# T6G (Grand Teton) — schematic netlist excerpt (pin names and nets, part order shuffled) for the footprints in the layout excerpt that follows; sources: Cadence DE-HDL packaged netlist, KiCad conversion of 04192023_DAF0TMB3IC0_F0TG_MB_C_brd_V02_OCP.brd

J107  CONN112_10137002101LF  CONN112_10137002-101LF IO  pkg HSD_F112D8_P2W1-2_RDH  page 117
  A1  = NC_J107_A1
  A2  = GND
  A3  = NC_J107_A3
  A4  = GND
  A5  = NC_J107_A5
  A6  = GND
  A7  = SWB_HSC_PWRGD
  A8  = GND
  B1  = GND
  B2  = P5E_CPU0_P0_RX_BUF_DN<9>
  B3  = GND
  B4  = P5E_CPU0_P0_RX_BUF_DN<11>
  B5  = GND
  B6  = P5E_CPU0_P0_RX_BUF_DN<13>
  B7  = GND
  B8  = P5E_CPU0_P0_RX_BUF_DN<15>
  C1  = P5E_CPU0_P0_RX_BUF_DN<8>
  C2  = P5E_CPU0_P0_RX_BUF_DP<9>
  C3  = P5E_CPU0_P0_RX_BUF_DN<10>
  C4  = P5E_CPU0_P0_RX_BUF_DP<11>
  C5  = P5E_CPU0_P0_RX_BUF_DN<12>
  C6  = P5E_CPU0_P0_RX_BUF_DP<13>
  C7  = P5E_CPU0_P0_RX_BUF_DN<14>
  C8  = P5E_CPU0_P0_RX_BUF_DP<15>
  D1  = P5E_CPU0_P0_RX_BUF_DP<8>
  D2  = GND
  D3  = P5E_CPU0_P0_RX_BUF_DP<10>
  D4  = GND
  D5  = P5E_CPU0_P0_RX_BUF_DP<12>
  D6  = GND
  D7  = P5E_CPU0_P0_RX_BUF_DP<14>
  D8  = GND
  E1  = GND
  E2  = P5E_CPU0_P1_RX_BUF_DN<9>
  E3  = GND
  E4  = P5E_CPU0_P1_RX_BUF_DN<11>
  E5  = GND
  E6  = P5E_CPU0_P1_RX_BUF_DN<13>
  E7  = GND
  E8  = P5E_CPU0_P1_RX_BUF_DN<15>
  F1  = P5E_CPU0_P1_RX_BUF_DN<8>
  F2  = P5E_CPU0_P1_RX_BUF_DP<9>
  F3  = P5E_CPU0_P1_RX_BUF_DN<10>
  F4  = P5E_CPU0_P1_RX_BUF_DP<11>
  F5  = P5E_CPU0_P1_RX_BUF_DN<12>
  F6  = P5E_CPU0_P1_RX_BUF_DP<13>
  F7  = P5E_CPU0_P1_RX_BUF_DN<14>
  F8  = P5E_CPU0_P1_RX_BUF_DP<15>
  G1  = P5E_CPU0_P1_RX_BUF_DP<8>
  G2  = GND
  G3  = P5E_CPU0_P1_RX_BUF_DP<10>
  G4  = GND
  G5  = P5E_CPU0_P1_RX_BUF_DP<12>
  G6  = GND
  G7  = P5E_CPU0_P1_RX_BUF_DP<14>
  G8  = GND
  H1  = GND
  H2  = P5E_CPU0_P0_TX_BUF_C_DN<9>
  H3  = GND
  H4  = P5E_CPU0_P0_TX_BUF_C_DN<11>
  H5  = GND
  H6  = P5E_CPU0_P0_TX_BUF_C_DN<13>
  H7  = GND
  H8  = P5E_CPU0_P0_TX_BUF_C_DN<15>
  I1  = P5E_CPU0_P0_TX_BUF_C_DN<8>
  I2  = P5E_CPU0_P0_TX_BUF_C_DP<9>
  I3  = P5E_CPU0_P0_TX_BUF_C_DN<10>
  I4  = P5E_CPU0_P0_TX_BUF_C_DP<11>
  I5  = P5E_CPU0_P0_TX_BUF_C_DN<12>
  I6  = P5E_CPU0_P0_TX_BUF_C_DP<13>
  I7  = P5E_CPU0_P0_TX_BUF_C_DN<14>
  I8  = P5E_CPU0_P0_TX_BUF_C_DP<15>
  J1  = P5E_CPU0_P0_TX_BUF_C_DP<8>
  J2  = GND
  J3  = P5E_CPU0_P0_TX_BUF_C_DP<10>
  J4  = GND
  J5  = P5E_CPU0_P0_TX_BUF_C_DP<12>
  J6  = GND
  J7  = P5E_CPU0_P0_TX_BUF_C_DP<14>
  J8  = GND
  K1  = GND
  K2  = P5E_CPU0_P1_TX_BUF_C_DN<9>
  K3  = GND
  K4  = P5E_CPU0_P1_TX_BUF_C_DN<11>
  K5  = GND
  K6  = P5E_CPU0_P1_TX_BUF_C_DN<13>
  K7  = GND
  K8  = P5E_CPU0_P1_TX_BUF_C_DN<15>
  L1  = P5E_CPU0_P1_TX_BUF_C_DN<8>
  L2  = P5E_CPU0_P1_TX_BUF_C_DP<9>
  L3  = P5E_CPU0_P1_TX_BUF_C_DN<10>
  L4  = P5E_CPU0_P1_TX_BUF_C_DP<11>
  L5  = P5E_CPU0_P1_TX_BUF_C_DN<12>
  L6  = P5E_CPU0_P1_TX_BUF_C_DP<13>
  L7  = P5E_CPU0_P1_TX_BUF_C_DN<14>
  L8  = P5E_CPU0_P1_TX_BUF_C_DP<15>
  M1  = P5E_CPU0_P1_TX_BUF_C_DP<8>
  M2  = GND
  M3  = P5E_CPU0_P1_TX_BUF_C_DP<10>
  M4  = GND
  M5  = P5E_CPU0_P1_TX_BUF_C_DP<12>
  M6  = GND
  M7  = P5E_CPU0_P1_TX_BUF_C_DP<14>
  M8  = GND
  N1  = GND
  N2  = PRSNT_CABLE_SWB_B2_N
  N3  = GND
  N4  = NC_J107_N4
  N5  = GND
  N6  = NC_J107_N6
  N7  = GND
  N8  = SWB_HSC_EN_BUF

(kicad_pcb
	(version 20260206)
	(generator "pcbnew")
	(generator_version "10.0")
	(general
		(thickness 1.6)
		(legacy_teardrops no)
	)
	(paper "A4")
	(title_block
		(title "04192023_DAF0TMB3IC0_F0TG_MB_C_brd_V02_OCP.brd")
		(comment 1 "Grand Teton / footprint 2835 of 8354 (J107), pads 32-48 of 48")
	)
	(layers
		(0 "F.Cu" signal "TOP")
		(4 "In1.Cu" signal "GND")
		(6 "In2.Cu" signal "IN1")
		(8 "In3.Cu" signal "GND1")
		(10 "In4.Cu" signal "IN2")
		(12 "In5.Cu" signal "GND2")
		(14 "In6.Cu" signal "IN3")
		(16 "In7.Cu" signal "GND3")
		(18 "In8.Cu" signal "VCC")
		(20 "In9.Cu" signal "VCC1")
		(22 "In10.Cu" signal "GND4")
		(24 "In11.Cu" signal "IN4")
		(26 "In12.Cu" signal "GND5")
		(28 "In13.Cu" signal "IN5")
		(30 "In14.Cu" signal "GND6")
		(32 "In15.Cu" signal "IN6")
		(34 "In16.Cu" signal "GND7")
		(2 "B.Cu" signal "BOTTOM")
		(9 "F.Adhes" user "F.Adhesive")
		(11 "B.Adhes" user "B.Adhesive")
		(13 "F.Paste" user "Package Geometry/Pastemask Top")
		(15 "B.Paste" user "Package Geometry/Pastemask Bottom")
		(5 "F.SilkS" user "Ref Des/Silkscreen Top")
		(7 "B.SilkS" user "Ref Des/Silkscreen Bottom")
		(1 "F.Mask" user "Board Geometry/Soldermask Top")
		(3 "B.Mask" user "Board Geometry/Soldermask Bottom")
		(17 "Dwgs.User" user "User.Drawings")
		(19 "Cmts.User" user "User.Comments")
		(21 "Eco1.User" user "User.Eco1")
		(23 "Eco2.User" user "User.Eco2")
		(25 "Edge.Cuts" user "Board Geometry/Outline")
		(27 "Margin" user)
		(31 "F.CrtYd" user "Package Geometry/Place Bound Top")
		(29 "B.CrtYd" user "Package Geometry/Place Bound Bottom")
		(35 "F.Fab" user "Ref Des/Assembly Top")
		(33 "B.Fab" user "Ref Des/Assembly Bottom")
	)
	(footprint ""
		(layer "F.Cu")
		(at 331.649832 -440.489848)
		(property "Reference" "J107"
			(at 19.92249 18.882106 0)
			(unlocked yes)
			(layer "F.SilkS")
			(effects
				(font
					(size 0.7874 0.5842)
					(thickness 0.1524)
				)
				(justify left)
			)
		)
		(property "Value" ""
			(at 0 0 0)
			(layer "F.Fab")
			(effects
				(font
					(size 1.27 1.27)
				)
			)
		)
		(duplicate_pad_numbers_are_jumpers no)
		(pad "J8" thru_hole circle
			(at 13.999972 10.999978 180)
			(size 0.906272 0.906272)
			(drill 0.499872)
			(layers "*.Cu" "*.Mask")
			(remove_unused_layers no)
			(net "GND")
			(clearance 0.0508)
			(thermal_gap 0.0508)
		)
		(pad "K1" thru_hole circle
			(at 0 11.999976 180)
			(size 0.906272 0.906272)
			(drill 0.499872)
			(layers "*.Cu" "*.Mask")
			(remove_unused_layers no)
			(net "GND")
			(clearance 0.0508)
			(thermal_gap 0.0508)
		)
		(pad "K3" thru_hole circle
			(at 3.999992 11.999976 180)
			(size 0.906272 0.906272)
			(drill 0.499872)
			(layers "*.Cu" "*.Mask")
			(remove_unused_layers no)
			(net "GND")
			(clearance 0.0508)
			(thermal_gap 0.0508)
		)
		(pad "K5" thru_hole circle
			(at 7.999984 11.999976 180)
			(size 0.906272 0.906272)
			(drill 0.499872)
			(layers "*.Cu" "*.Mask")
			(remove_unused_layers no)
			(net "GND")
			(clearance 0.0508)
			(thermal_gap 0.0508)
		)
		(pad "K7" thru_hole circle
			(at 11.999976 11.999976 180)
			(size 0.906272 0.906272)
			(drill 0.499872)
			(layers "*.Cu" "*.Mask")
			(remove_unused_layers no)
			(net "GND")
			(clearance 0.0508)
			(thermal_gap 0.0508)
		)
		(pad "M2" thru_hole circle
			(at 1.999996 14.59992 180)
			(size 0.906272 0.906272)
			(drill 0.499872)
			(layers "*.Cu" "*.Mask")
			(remove_unused_layers no)
			(net "GND")
			(clearance 0.0508)
			(thermal_gap 0.0508)
		)
		(pad "M4" thru_hole circle
			(at 5.999988 14.59992 180)
			(size 0.906272 0.906272)
			(drill 0.499872)
			(layers "*.Cu" "*.Mask")
			(remove_unused_layers no)
			(net "GND")
			(clearance 0.0508)
			(thermal_gap 0.0508)
		)
		(pad "M6" thru_hole circle
			(at 9.99998 14.59992 180)
			(size 0.906272 0.906272)
			(drill 0.499872)
			(layers "*.Cu" "*.Mask")
			(remove_unused_layers no)
			(net "GND")
			(clearance 0.0508)
			(thermal_gap 0.0508)
		)
		(pad "M8" thru_hole circle
			(at 13.999972 14.59992 180)
			(size 0.906272 0.906272)
			(drill 0.499872)
			(layers "*.Cu" "*.Mask")
			(remove_unused_layers no)
			(net "GND")
			(clearance 0.0508)
			(thermal_gap 0.0508)
		)
		(pad "N1" thru_hole circle
			(at 0 15.599918 180)
			(size 0.906272 0.906272)
			(drill 0.499872)
			(layers "*.Cu" "*.Mask")
			(remove_unused_layers no)
			(net "GND")
			(clearance 0.0508)
			(thermal_gap 0.0508)
		)
		(pad "N2" thru_hole circle
			(at 1.999996 15.80007 180)
			(size 0.766318 0.766318)
			(drill 0.359918)
			(layers "*.Cu" "*.Mask")
			(remove_unused_layers no)
			(net "PRSNT_CABLE_SWB_B2_N")
			(clearance 0.0508)
			(thermal_gap 0.0508)
		)
		(pad "N3" thru_hole circle
			(at 3.999992 15.599918 180)
			(size 0.906272 0.906272)
			(drill 0.499872)
			(layers "*.Cu" "*.Mask")
			(remove_unused_layers no)
			(net "GND")
			(clearance 0.0508)
			(thermal_gap 0.0508)
		)
		(pad "N4" thru_hole circle
			(at 5.999988 15.80007 180)
			(size 0.766318 0.766318)
			(drill 0.359918)
			(layers "*.Cu" "*.Mask")
			(remove_unused_layers no)
			(net "NC_J107_N4")
			(clearance 0.0508)
			(thermal_gap 0.0508)
		)
		(pad "N5" thru_hole circle
			(at 7.999984 15.599918 180)
			(size 0.906272 0.906272)
			(drill 0.499872)
			(layers "*.Cu" "*.Mask")
			(remove_unused_layers no)
			(net "GND")
			(clearance 0.0508)
			(thermal_gap 0.0508)
		)
		(pad "N6" thru_hole circle
			(at 9.99998 15.80007 180)
			(size 0.766318 0.766318)
			(drill 0.359918)
			(layers "*.Cu" "*.Mask")
			(remove_unused_layers no)
			(net "NC_J107_N6")
			(clearance 0.0508)
			(thermal_gap 0.0508)
		)
		(pad "N7" thru_hole circle
			(at 11.999976 15.599918 180)
			(size 0.906272 0.906272)
			(drill 0.499872)
			(layers "*.Cu" "*.Mask")
			(remove_unused_layers no)
			(net "GND")
			(clearance 0.0508)
			(thermal_gap 0.0508)
		)
		(pad "N8" thru_hole circle
			(at 13.999972 15.80007 180)
			(size 0.766318 0.766318)
			(drill 0.359918)
			(layers "*.Cu" "*.Mask")
			(remove_unused_layers no)
			(net "SWB_HSC_EN_BUF")
			(clearance 0.0508)
			(thermal_gap 0.0508)
		)
	)
)
